(kicad_pcb
	(version 20260206)
	(generator "pcbnew")
	(generator_version "10.0")
	(general
		(thickness 1.6)
		(legacy_teardrops no)
	)
	(paper "A4")
	(title_block
		(title "04192023_DAF0TMB3IC0_F0TG_MB_C_brd_V02_OCP.brd")
		(comment 1 "Grand Teton / footprints 4372-4377 of 8354")
	)
	(layers
		(0 "F.Cu" signal "TOP")
		(4 "In1.Cu" signal "GND")
		(6 "In2.Cu" signal "IN1")
		(8 "In3.Cu" signal "GND1")
		(10 "In4.Cu" signal "IN2")
		(12 "In5.Cu" signal "GND2")
		(14 "In6.Cu" signal "IN3")
		(16 "In7.Cu" signal "GND3")
		(18 "In8.Cu" signal "VCC")
		(20 "In9.Cu" signal "VCC1")
		(22 "In10.Cu" signal "GND4")
		(24 "In11.Cu" signal "IN4")
		(26 "In12.Cu" signal "GND5")
		(28 "In13.Cu" signal "IN5")
		(30 "In14.Cu" signal "GND6")
		(32 "In15.Cu" signal "IN6")
		(34 "In16.Cu" signal "GND7")
		(2 "B.Cu" signal "BOTTOM")
		(9 "F.Adhes" user "F.Adhesive")
		(11 "B.Adhes" user "B.Adhesive")
		(13 "F.Paste" user "Package Geometry/Pastemask Top")
		(15 "B.Paste" user "Package Geometry/Pastemask Bottom")
		(5 "F.SilkS" user "Ref Des/Silkscreen Top")
		(7 "B.SilkS" user "Ref Des/Silkscreen Bottom")
		(1 "F.Mask" user "Board Geometry/Soldermask Top")
		(3 "B.Mask" user "Board Geometry/Soldermask Bottom")
		(17 "Dwgs.User" user "User.Drawings")
		(19 "Cmts.User" user "User.Comments")
		(21 "Eco1.User" user "User.Eco1")
		(23 "Eco2.User" user "User.Eco2")
		(25 "Edge.Cuts" user "Board Geometry/Outline")
		(27 "Margin" user)
		(31 "F.CrtYd" user "Package Geometry/Place Bound Top")
		(29 "B.CrtYd" user "Package Geometry/Place Bound Bottom")
		(35 "F.Fab" user "Ref Des/Assembly Top")
		(33 "B.Fab" user "Ref Des/Assembly Bottom")
	)
	(footprint ""
		(layer "F.Cu")
		(at 453.054212 -24.619458 180)
		(property "Reference" "PC2088"
			(at 0 0 180)
			(layer "F.SilkS")
			(hide yes)
			(effects
				(font
					(size 1.27 1.27)
				)
			)
		)
		(property "Value" ""
			(at 0 0 180)
			(layer "F.Fab")
			(effects
				(font
					(size 1.27 1.27)
				)
			)
		)
		(duplicate_pad_numbers_are_jumpers no)
		(fp_line
			(start 0.7874 0.4064)
			(end -0.7874 0.4064)
			(stroke
				(width 0.1524)
				(type default)
			)
			(layer "F.SilkS")
		)
		(fp_line
			(start 0.7874 -0.4064)
			(end 0.7874 0.4064)
			(stroke
				(width 0.1524)
				(type default)
			)
			(layer "F.SilkS")
		)
		(fp_line
			(start -0.7874 0.4064)
			(end -0.7874 -0.4064)
			(stroke
				(width 0.1524)
				(type default)
			)
			(layer "F.SilkS")
		)
		(fp_line
			(start -0.7874 -0.4064)
			(end 0.7874 -0.4064)
			(stroke
				(width 0.1524)
				(type default)
			)
			(layer "F.SilkS")
		)
		(fp_line
			(start 0.67945 0.3048)
			(end 0.120396 0.3048)
			(stroke
				(width 0.1)
				(type default)
			)
			(layer "F.Fab")
		)
		(fp_line
			(start 0.67945 -0.3048)
			(end 0.67945 0.3048)
			(stroke
				(width 0.1)
				(type default)
			)
			(layer "F.Fab")
		)
		(fp_line
			(start 0.12065 -0.2794)
			(end 0.12065 -0.3048)
			(stroke
				(width 0.1)
				(type default)
			)
			(layer "F.Fab")
		)
		(fp_line
			(start 0.12065 -0.3048)
			(end 0.67945 -0.3048)
			(stroke
				(width 0.1)
				(type default)
			)
			(layer "F.Fab")
		)
		(fp_line
			(start 0.120396 0.3048)
			(end 0.120396 0.2794)
			(stroke
				(width 0.1)
				(type default)
			)
			(layer "F.Fab")
		)
		(fp_line
			(start 0.120396 0.2794)
			(end -0.12065 0.2794)
			(stroke
				(width 0.1)
				(type default)
			)
			(layer "F.Fab")
		)
		(fp_line
			(start -0.12065 0.3048)
			(end -0.67945 0.3048)
			(stroke
				(width 0.1)
				(type default)
			)
			(layer "F.Fab")
		)
		(fp_line
			(start -0.12065 0.2794)
			(end -0.12065 0.3048)
			(stroke
				(width 0.1)
				(type default)
			)
			(layer "F.Fab")
		)
		(fp_line
			(start -0.12065 -0.2794)
			(end 0.12065 -0.2794)
			(stroke
				(width 0.1)
				(type default)
			)
			(layer "F.Fab")
		)
		(fp_line
			(start -0.12065 -0.305054)
			(end -0.12065 -0.2794)
			(stroke
				(width 0.1)
				(type default)
			)
			(layer "F.Fab")
		)
		(fp_line
			(start -0.67945 0.3048)
			(end -0.67945 -0.305054)
			(stroke
				(width 0.1)
				(type default)
			)
			(layer "F.Fab")
		)
		(fp_line
			(start -0.67945 -0.305054)
			(end -0.12065 -0.305054)
			(stroke
				(width 0.1)
				(type default)
			)
			(layer "F.Fab")
		)
		(pad "1" smd circle
			(at -0.40005 0 180)
			(size 0 0)
			(layers "F.Cu" "F.Mask" "F.Paste")
			(net "P12V_OCP_SFF")
		)
		(pad "2" smd circle
			(at 0.40005 0 180)
			(size 0 0)
			(layers "F.Cu" "F.Mask" "F.Paste")
			(net "P12V_OCP_GATE_1")
		)
	)
	(footprint ""
		(layer "F.Cu")
		(at 120.76049 -52.86629 90)
		(property "Reference" "R6108"
			(at 0 0 90)
			(layer "F.SilkS")
			(hide yes)
			(effects
				(font
					(size 1.27 1.27)
				)
			)
		)
		(property "Value" ""
			(at 0 0 90)
			(layer "F.Fab")
			(effects
				(font
					(size 1.27 1.27)
				)
			)
		)
		(duplicate_pad_numbers_are_jumpers no)
		(fp_line
			(start 0.7874 -0.4064)
			(end 0.7874 0.4064)
			(stroke
				(width 0.1524)
				(type default)
			)
			(layer "F.SilkS")
		)
		(fp_line
			(start -0.7874 -0.4064)
			(end 0.7874 -0.4064)
			(stroke
				(width 0.1524)
				(type default)
			)
			(layer "F.SilkS")
		)
		(fp_line
			(start 0.7874 0.4064)
			(end -0.7874 0.4064)
			(stroke
				(width 0.1524)
				(type default)
			)
			(layer "F.SilkS")
		)
		(fp_line
			(start -0.7874 0.4064)
			(end -0.7874 -0.4064)
			(stroke
				(width 0.1524)
				(type default)
			)
			(layer "F.SilkS")
		)
		(fp_line
			(start -0.12065 -0.305054)
			(end -0.12065 -0.2794)
			(stroke
				(width 0.1)
				(type default)
			)
			(layer "F.Fab")
		)
		(fp_line
			(start -0.67945 -0.305054)
			(end -0.12065 -0.305054)
			(stroke
				(width 0.1)
				(type default)
			)
			(layer "F.Fab")
		)
		(fp_line
			(start 0.67945 -0.3048)
			(end 0.67945 0.3048)
			(stroke
				(width 0.1)
				(type default)
			)
			(layer "F.Fab")
		)
		(fp_line
			(start 0.12065 -0.3048)
			(end 0.67945 -0.3048)
			(stroke
				(width 0.1)
				(type default)
			)
			(layer "F.Fab")
		)
		(fp_line
			(start 0.12065 -0.2794)
			(end 0.12065 -0.3048)
			(stroke
				(width 0.1)
				(type default)
			)
			(layer "F.Fab")
		)
		(fp_line
			(start -0.12065 -0.2794)
			(end 0.12065 -0.2794)
			(stroke
				(width 0.1)
				(type default)
			)
			(layer "F.Fab")
		)
		(fp_line
			(start 0.120396 0.2794)
			(end -0.12065 0.2794)
			(stroke
				(width 0.1)
				(type default)
			)
			(layer "F.Fab")
		)
		(fp_line
			(start -0.12065 0.2794)
			(end -0.12065 0.3048)
			(stroke
				(width 0.1)
				(type default)
			)
			(layer "F.Fab")
		)
		(fp_line
			(start 0.67945 0.3048)
			(end 0.120396 0.3048)
			(stroke
				(width 0.1)
				(type default)
			)
			(layer "F.Fab")
		)
		(fp_line
			(start 0.120396 0.3048)
			(end 0.120396 0.2794)
			(stroke
				(width 0.1)
				(type default)
			)
			(layer "F.Fab")
		)
		(fp_line
			(start -0.12065 0.3048)
			(end -0.67945 0.3048)
			(stroke
				(width 0.1)
				(type default)
			)
			(layer "F.Fab")
		)
		(fp_line
			(start -0.67945 0.3048)
			(end -0.67945 -0.305054)
			(stroke
				(width 0.1)
				(type default)
			)
			(layer "F.Fab")
		)
		(pad "1" smd circle
			(at -0.40005 0 90)
			(size 0 0)
			(layers "F.Cu" "F.Mask" "F.Paste")
			(net "HDT_HDR_TDO")
		)
		(pad "2" smd circle
			(at 0.40005 0 90)
			(size 0 0)
			(layers "F.Cu" "F.Mask" "F.Paste")
			(net "HDT_HDR_TDO_R")
		)
	)
	(footprint ""
		(layer "F.Cu")
		(at 327.179178 -43.573954)
		(property "Reference" "R1791"
			(at 0 0 0)
			(layer "F.SilkS")
			(hide yes)
			(effects
				(font
					(size 1.27 1.27)
				)
			)
		)
		(property "Value" ""
			(at 0 0 0)
			(layer "F.Fab")
			(effects
				(font
					(size 1.27 1.27)
				)
			)
		)
		(duplicate_pad_numbers_are_jumpers no)
		(fp_line
			(start -0.7874 -0.4064)
			(end 0.7874 -0.4064)
			(stroke
				(width 0.1524)
				(type default)
			)
			(layer "F.SilkS")
		)
		(fp_line
			(start -0.7874 0.4064)
			(end -0.7874 -0.4064)
			(stroke
				(width 0.1524)
				(type default)
			)
			(layer "F.SilkS")
		)
		(fp_line
			(start 0.7874 -0.4064)
			(end 0.7874 0.4064)
			(stroke
				(width 0.1524)
				(type default)
			)
			(layer "F.SilkS")
		)
		(fp_line
			(start 0.7874 0.4064)
			(end -0.7874 0.4064)
			(stroke
				(width 0.1524)
				(type default)
			)
			(layer "F.SilkS")
		)
		(fp_line
			(start -0.67945 -0.305054)
			(end -0.12065 -0.305054)
			(stroke
				(width 0.1)
				(type default)
			)
			(layer "F.Fab")
		)
		(fp_line
			(start -0.67945 0.3048)
			(end -0.67945 -0.305054)
			(stroke
				(width 0.1)
				(type default)
			)
			(layer "F.Fab")
		)
		(fp_line
			(start -0.12065 -0.305054)
			(end -0.12065 -0.2794)
			(stroke
				(width 0.1)
				(type default)
			)
			(layer "F.Fab")
		)
		(fp_line
			(start -0.12065 -0.2794)
			(end 0.12065 -0.2794)
			(stroke
				(width 0.1)
				(type default)
			)
			(layer "F.Fab")
		)
		(fp_line
			(start -0.12065 0.2794)
			(end -0.12065 0.3048)
			(stroke
				(width 0.1)
				(type default)
			)
			(layer "F.Fab")
		)
		(fp_line
			(start -0.12065 0.3048)
			(end -0.67945 0.3048)
			(stroke
				(width 0.1)
				(type default)
			)
			(layer "F.Fab")
		)
		(fp_line
			(start 0.120396 0.2794)
			(end -0.12065 0.2794)
			(stroke
				(width 0.1)
				(type default)
			)
			(layer "F.Fab")
		)
		(fp_line
			(start 0.120396 0.3048)
			(end 0.120396 0.2794)
			(stroke
				(width 0.1)
				(type default)
			)
			(layer "F.Fab")
		)
		(fp_line
			(start 0.12065 -0.3048)
			(end 0.67945 -0.3048)
			(stroke
				(width 0.1)
				(type default)
			)
			(layer "F.Fab")
		)
		(fp_line
			(start 0.12065 -0.2794)
			(end 0.12065 -0.3048)
			(stroke
				(width 0.1)
				(type default)
			)
			(layer "F.Fab")
		)
		(fp_line
			(start 0.67945 -0.3048)
			(end 0.67945 0.3048)
			(stroke
				(width 0.1)
				(type default)
			)
			(layer "F.Fab")
		)
		(fp_line
			(start 0.67945 0.3048)
			(end 0.120396 0.3048)
			(stroke
				(width 0.1)
				(type default)
			)
			(layer "F.Fab")
		)
		(pad "1" smd circle
			(at -0.40005 0)
			(size 0 0)
			(layers "F.Cu" "F.Mask" "F.Paste")
			(net "P5V_ADC")
		)
		(pad "2" smd circle
			(at 0.40005 0)
			(size 0 0)
			(layers "F.Cu" "F.Mask" "F.Paste")
			(net "GND")
		)
	)
	(footprint ""
		(layer "F.Cu")
		(at 167.386 -95.377 90)
		(property "Reference" "U30"
			(at -3.544316 -2.646172 90)
			(unlocked yes)
			(layer "F.SilkS")
			(effects
				(font
					(size 0.7874 0.5842)
					(thickness 0.1524)
				)
				(justify left)
			)
		)
		(property "Value" ""
			(at 0 0 90)
			(layer "F.Fab")
			(effects
				(font
					(size 1.27 1.27)
				)
			)
		)
		(duplicate_pad_numbers_are_jumpers no)
		(fp_line
			(start 2.0574 -1.651)
			(end 2.0574 1.651)
			(stroke
				(width 0.1524)
				(type default)
			)
			(layer "F.SilkS")
		)
		(fp_line
			(start 0.381 -1.651)
			(end 2.0574 -1.651)
			(stroke
				(width 0.1524)
				(type default)
			)
			(layer "F.SilkS")
		)
		(fp_line
			(start -0.381 -1.651)
			(end 0 -1.016)
			(stroke
				(width 0.1524)
				(type default)
			)
			(layer "F.SilkS")
		)
		(fp_line
			(start -2.0574 -1.651)
			(end -0.381 -1.651)
			(stroke
				(width 0.1524)
				(type default)
			)
			(layer "F.SilkS")
		)
		(fp_line
			(start 0 -1.016)
			(end 0.381 -1.651)
			(stroke
				(width 0.1524)
				(type default)
			)
			(layer "F.SilkS")
		)
		(fp_line
			(start 2.0574 1.651)
			(end -2.0574 1.651)
			(stroke
				(width 0.1524)
				(type default)
			)
			(layer "F.SilkS")
		)
		(fp_line
			(start -2.0574 1.651)
			(end -2.0574 -1.651)
			(stroke
				(width 0.1524)
				(type default)
			)
			(layer "F.SilkS")
		)
		(fp_poly
			(pts
				(xy -2.71272 -0.719328) (xy -2.71272 -1.344168) (xy -2.159 -1.016)
			)
			(stroke
				(width 0)
				(type default)
			)
			(fill yes)
			(layer "F.SilkS")
		)
		(fp_line
			(start 0.899922 -1.549908)
			(end 0.899922 -1.199896)
			(stroke
				(width 0.1)
				(type default)
			)
			(layer "F.Fab")
		)
		(fp_line
			(start -0.899922 -1.549908)
			(end 0.899922 -1.549908)
			(stroke
				(width 0.1)
				(type default)
			)
			(layer "F.Fab")
		)
		(fp_line
			(start 1.599946 -1.199896)
			(end 1.599946 1.199896)
			(stroke
				(width 0.1)
				(type default)
			)
			(layer "F.Fab")
		)
		(fp_line
			(start 0.899922 -1.199896)
			(end 1.599946 -1.199896)
			(stroke
				(width 0.1)
				(type default)
			)
			(layer "F.Fab")
		)
		(fp_line
			(start -0.899922 -1.199896)
			(end -0.899922 -1.549908)
			(stroke
				(width 0.1)
				(type default)
			)
			(layer "F.Fab")
		)
		(fp_line
			(start -1.599946 -1.199896)
			(end -0.899922 -1.199896)
			(stroke
				(width 0.1)
				(type default)
			)
			(layer "F.Fab")
		)
		(fp_line
			(start 1.599946 1.199896)
			(end 0.899922 1.199896)
			(stroke
				(width 0.1)
				(type default)
			)
			(layer "F.Fab")
		)
		(fp_line
			(start 0.899922 1.199896)
			(end 0.899922 1.549908)
			(stroke
				(width 0.1)
				(type default)
			)
			(layer "F.Fab")
		)
		(fp_line
			(start -0.899922 1.199896)
			(end -1.599946 1.199896)
			(stroke
				(width 0.1)
				(type default)
			)
			(layer "F.Fab")
		)
		(fp_line
			(start -1.599946 1.199896)
			(end -1.599946 -1.199896)
			(stroke
				(width 0.1)
				(type default)
			)
			(layer "F.Fab")
		)
		(fp_line
			(start 0.899922 1.549908)
			(end -0.899922 1.549908)
			(stroke
				(width 0.1)
				(type default)
			)
			(layer "F.Fab")
		)
		(fp_line
			(start -0.899922 1.549908)
			(end -0.899922 1.199896)
			(stroke
				(width 0.1)
				(type default)
			)
			(layer "F.Fab")
		)
		(fp_poly
			(pts
				(xy -2.71272 -0.719328) (xy -2.71272 -1.344168) (xy -2.159 -1.016)
			)
			(stroke
				(width 0)
				(type default)
			)
			(fill yes)
			(layer "F.Fab")
		)
		(pad "1" smd rect
			(at -1.225042 -0.94996)
			(size 0.5588 1.3462)
			(layers "F.Cu" "F.Mask" "F.Paste")
			(net "Net_10854")
		)
		(pad "2" smd rect
			(at -1.225042 0)
			(size 0.5588 1.3462)
			(layers "F.Cu" "F.Mask" "F.Paste")
			(net "OCP_V3_1_P3V3_R2_PWRGD")
		)
		(pad "3" smd rect
			(at -1.225042 0.94996)
			(size 0.5588 1.3462)
			(layers "F.Cu" "F.Mask" "F.Paste")
			(net "GND")
		)
		(pad "4" smd rect
			(at 1.225042 0.94996)
			(size 0.5588 1.3462)
			(layers "F.Cu" "F.Mask" "F.Paste")
			(net "OCP_V3_1_P3V3_PLD_PWRGD")
		)
		(pad "5" smd rect
			(at 1.225042 -0.94996)
			(size 0.5588 1.3462)
			(layers "F.Cu" "F.Mask" "F.Paste")
			(net "P3V3_AUX")
		)
	)
	(footprint ""
		(layer "F.Cu")
		(at 329.2348 -15.979394 -90)
		(property "Reference" "R1194"
			(at 0 0 270)
			(layer "F.SilkS")
			(hide yes)
			(effects
				(font
					(size 1.27 1.27)
				)
			)
		)
		(property "Value" ""
			(at 0 0 270)
			(layer "F.Fab")
			(effects
				(font
					(size 1.27 1.27)
				)
			)
		)
		(duplicate_pad_numbers_are_jumpers no)
		(fp_line
			(start -0.7874 0.4064)
			(end -0.7874 -0.4064)
			(stroke
				(width 0.1524)
				(type default)
			)
			(layer "F.SilkS")
		)
		(fp_line
			(start 0.7874 0.4064)
			(end -0.7874 0.4064)
			(stroke
				(width 0.1524)
				(type default)
			)
			(layer "F.SilkS")
		)
		(fp_line
			(start -0.7874 -0.4064)
			(end 0.7874 -0.4064)
			(stroke
				(width 0.1524)
				(type default)
			)
			(layer "F.SilkS")
		)
		(fp_line
			(start 0.7874 -0.4064)
			(end 0.7874 0.4064)
			(stroke
				(width 0.1524)
				(type default)
			)
			(layer "F.SilkS")
		)
		(fp_line
			(start -0.67945 0.3048)
			(end -0.67945 -0.305054)
			(stroke
				(width 0.1)
				(type default)
			)
			(layer "F.Fab")
		)
		(fp_line
			(start -0.12065 0.3048)
			(end -0.67945 0.3048)
			(stroke
				(width 0.1)
				(type default)
			)
			(layer "F.Fab")
		)
		(fp_line
			(start 0.120396 0.3048)
			(end 0.120396 0.2794)
			(stroke
				(width 0.1)
				(type default)
			)
			(layer "F.Fab")
		)
		(fp_line
			(start 0.67945 0.3048)
			(end 0.120396 0.3048)
			(stroke
				(width 0.1)
				(type default)
			)
			(layer "F.Fab")
		)
		(fp_line
			(start -0.12065 0.2794)
			(end -0.12065 0.3048)
			(stroke
				(width 0.1)
				(type default)
			)
			(layer "F.Fab")
		)
		(fp_line
			(start 0.120396 0.2794)
			(end -0.12065 0.2794)
			(stroke
				(width 0.1)
				(type default)
			)
			(layer "F.Fab")
		)
		(fp_line
			(start -0.12065 -0.2794)
			(end 0.12065 -0.2794)
			(stroke
				(width 0.1)
				(type default)
			)
			(layer "F.Fab")
		)
		(fp_line
			(start 0.12065 -0.2794)
			(end 0.12065 -0.3048)
			(stroke
				(width 0.1)
				(type default)
			)
			(layer "F.Fab")
		)
		(fp_line
			(start 0.12065 -0.3048)
			(end 0.67945 -0.3048)
			(stroke
				(width 0.1)
				(type default)
			)
			(layer "F.Fab")
		)
		(fp_line
			(start 0.67945 -0.3048)
			(end 0.67945 0.3048)
			(stroke
				(width 0.1)
				(type default)
			)
			(layer "F.Fab")
		)
		(fp_line
			(start -0.67945 -0.305054)
			(end -0.12065 -0.305054)
			(stroke
				(width 0.1)
				(type default)
			)
			(layer "F.Fab")
		)
		(fp_line
			(start -0.12065 -0.305054)
			(end -0.12065 -0.2794)
			(stroke
				(width 0.1)
				(type default)
			)
			(layer "F.Fab")
		)
		(pad "1" smd circle
			(at -0.40005 0 270)
			(size 0 0)
			(layers "F.Cu" "F.Mask" "F.Paste")
			(net "P3V3_AUX")
		)
		(pad "2" smd circle
			(at 0.40005 0 270)
			(size 0 0)
			(layers "F.Cu" "F.Mask" "F.Paste")
			(net "BMC_FPGA_LED2_R_N")
		)
	)
	(footprint ""
		(layer "F.Cu")
		(at 20.480782 -409.421584 180)
		(property "Reference" "R665"
			(at 0 0 180)
			(layer "F.SilkS")
			(hide yes)
			(effects
				(font
					(size 1.27 1.27)
				)
			)
		)
		(property "Value" ""
			(at 0 0 180)
			(layer "F.Fab")
			(effects
				(font
					(size 1.27 1.27)
				)
			)
		)
		(duplicate_pad_numbers_are_jumpers no)
		(fp_line
			(start 0.7874 0.4064)
			(end -0.7874 0.4064)
			(stroke
				(width 0.1524)
				(type default)
			)
			(layer "F.SilkS")
		)
		(fp_line
			(start 0.7874 -0.4064)
			(end 0.7874 0.4064)
			(stroke
				(width 0.1524)
				(type default)
			)
			(layer "F.SilkS")
		)
		(fp_line
			(start -0.7874 0.4064)
			(end -0.7874 -0.4064)
			(stroke
				(width 0.1524)
				(type default)
			)
			(layer "F.SilkS")
		)
		(fp_line
			(start -0.7874 -0.4064)
			(end 0.7874 -0.4064)
			(stroke
				(width 0.1524)
				(type default)
			)
			(layer "F.SilkS")
		)
		(fp_line
			(start 0.67945 0.3048)
			(end 0.120396 0.3048)
			(stroke
				(width 0.1)
				(type default)
			)
			(layer "F.Fab")
		)
		(fp_line
			(start 0.67945 -0.3048)
			(end 0.67945 0.3048)
			(stroke
				(width 0.1)
				(type default)
			)
			(layer "F.Fab")
		)
		(fp_line
			(start 0.12065 -0.2794)
			(end 0.12065 -0.3048)
			(stroke
				(width 0.1)
				(type default)
			)
			(layer "F.Fab")
		)
		(fp_line
			(start 0.12065 -0.3048)
			(end 0.67945 -0.3048)
			(stroke
				(width 0.1)
				(type default)
			)
			(layer "F.Fab")
		)
		(fp_line
			(start 0.120396 0.3048)
			(end 0.120396 0.2794)
			(stroke
				(width 0.1)
				(type default)
			)
			(layer "F.Fab")
		)
		(fp_line
			(start 0.120396 0.2794)
			(end -0.12065 0.2794)
			(stroke
				(width 0.1)
				(type default)
			)
			(layer "F.Fab")
		)
		(fp_line
			(start -0.12065 0.3048)
			(end -0.67945 0.3048)
			(stroke
				(width 0.1)
				(type default)
			)
			(layer "F.Fab")
		)
		(fp_line
			(start -0.12065 0.2794)
			(end -0.12065 0.3048)
			(stroke
				(width 0.1)
				(type default)
			)
			(layer "F.Fab")
		)
		(fp_line
			(start -0.12065 -0.2794)
			(end 0.12065 -0.2794)
			(stroke
				(width 0.1)
				(type default)
			)
			(layer "F.Fab")
		)
		(fp_line
			(start -0.12065 -0.305054)
			(end -0.12065 -0.2794)
			(stroke
				(width 0.1)
				(type default)
			)
			(layer "F.Fab")
		)
		(fp_line
			(start -0.67945 0.3048)
			(end -0.67945 -0.305054)
			(stroke
				(width 0.1)
				(type default)
			)
			(layer "F.Fab")
		)
		(fp_line
			(start -0.67945 -0.305054)
			(end -0.12065 -0.305054)
			(stroke
				(width 0.1)
				(type default)
			)
			(layer "F.Fab")
		)
		(pad "1" smd circle
			(at -0.40005 0 180)
			(size 0 0)
			(layers "F.Cu" "F.Mask" "F.Paste")
			(net "P3V3_AUX")
		)
		(pad "2" smd circle
			(at 0.40005 0 180)
			(size 0 0)
			(layers "F.Cu" "F.Mask" "F.Paste")
			(net "P0V9_RETIMER_CPU1_INALERT")
		)
	)
)
